(kicad_pcb
	(version 20221018)
	(generator pcbnew)
	(general
    (thickness 1.656)
  )
	(paper "A4")
	(title_block
    (title "SDI-MIPI Bridge")
    (date "2023-08-09")
    (rev "1.3.4")
    (company "Antmicro")
		(comment 9 "footprints 145-154 of 190")
	)
	(layers
    (0 "F.Cu" signal)
    (1 "In1.Cu" power)
    (2 "In2.Cu" power)
    (3 "In3.Cu" signal)
    (4 "In4.Cu" signal)
    (31 "B.Cu" signal)
    (32 "B.Adhes" user "B.Adhesive")
    (33 "F.Adhes" user "F.Adhesive")
    (34 "B.Paste" user)
    (35 "F.Paste" user)
    (36 "B.SilkS" user "B.Silkscreen")
    (37 "F.SilkS" user "F.Silkscreen")
    (38 "B.Mask" user)
    (39 "F.Mask" user)
    (40 "Dwgs.User" user "User.Drawings")
    (41 "Cmts.User" user "User.Comments")
    (42 "Eco1.User" user "User.Eco1")
    (43 "Eco2.User" user "User.Eco2")
    (44 "Edge.Cuts" user)
    (45 "Margin" user)
    (46 "B.CrtYd" user "B.Courtyard")
    (47 "F.CrtYd" user "F.Courtyard")
    (48 "B.Fab" user)
    (49 "F.Fab" user)
  )
	(footprint "sdi-mipi-bridge-footprints:C_0402_1005Metric" (layer "B.Cu")
    (at 131.8 132.93 90)
    (descr "Capacitor SMD 0402")
    (tags "capacitor SMD 0402")
    (property "Author" "Antmicro")
    (property "Dielectric" "X7R")
    (property "License" "Apache-2.0")
    (property "MPN" "GRM155R71H103KA88D")
    (property "Manufacturer" "Murata")
    (property "Sheetfile" "sdi-mipi-bridge.kicad_sch")
    (property "Sheetname" "")
    (property "Val" "10n")
    (property "Voltage" "50V")
    (property "ki_description" " ")
    (attr smd)
    (fp_text reference "C10" (at 0.93 0.4 90) (layer "B.SilkS")
        (effects (font (size 0.7 0.7) (thickness 0.15)) (justify right bottom mirror))
    )
    (fp_text value "C_10n_0402" (at 0 -1.4 90) (layer "B.Fab") hide
        (effects (font (size 0.7 0.7) (thickness 0.15)) (justify right bottom mirror))
    )
    (fp_text user "License: Apache-2.0" (at -0.932 -5.17 90) (layer "B.Fab") hide
        (effects (font (size 0.7 0.7) (thickness 0.15)) (justify right bottom mirror))
    )
    (fp_text user "Author: Antmicro" (at -0.932 -4.17 90) (layer "B.Fab") hide
        (effects (font (size 0.7 0.7) (thickness 0.15)) (justify right bottom mirror))
    )
    (fp_text user "${REFERENCE}" (at -0.932 -3.168 90) (layer "B.Fab") hide
        (effects (font (size 0.7 0.7) (thickness 0.15)) (justify right bottom mirror))
    )
    (fp_rect (start -0.94 0.47) (end 0.94 -0.47)
      (stroke (width 0.05) (type solid)) (fill none) (layer "B.CrtYd"))
    (fp_rect (start -0.499 0.249) (end 0.499 -0.249)
      (stroke (width 0.15) (type solid)) (fill none) (layer "B.Fab"))
    (pad "1" smd roundrect (at -0.484 0 90) (size 0.59 0.64) (layers "B.Cu" "B.Paste" "B.Mask") (roundrect_rratio 0.25)
      (net 25 "Net-(U1-BYP)") (pintype "passive"))
    (pad "2" smd roundrect (at 0.484 0 90) (size 0.59 0.64) (layers "B.Cu" "B.Paste" "B.Mask") (roundrect_rratio 0.25)
      (net 2 "+1V2") (pintype "passive"))
  )
	(footprint "sdi-mipi-bridge-footprints:R_0402_1005Metric" (layer "B.Cu")
    (at 147.925 112.925 -90)
    (descr "Resistor SMD 0402")
    (tags "resistor SMD 0402")
    (property "Author" "Antmicro")
    (property "Current" "1A")
    (property "License" "Apache-2.0")
    (property "MPN" "ERJ2GE0R00X")
    (property "Manufacturer" "Panasonic")
    (property "Sheetfile" "sdi-mipi-bridge.kicad_sch")
    (property "Sheetname" "")
    (property "Tolerance" "")
    (property "Val" "0R")
    (property "ki_description" "0R resistor in 0402 package with unspecified tolerance")
    (attr smd)
    (fp_text reference "R90" (at 6.675 -9.275 90) (layer "B.SilkS")
        (effects (font (size 0.7 0.7) (thickness 0.15)) (justify left bottom mirror))
    )
    (fp_text value "R_0R_0402" (at 0 -1.4 90) (layer "B.Fab") hide
        (effects (font (size 0.7 0.7) (thickness 0.15)) (justify left bottom mirror))
    )
    (fp_text user "Author: Antmicro" (at -0.95 -4.169 90) (layer "B.Fab") hide
        (effects (font (size 0.7 0.7) (thickness 0.15)) (justify left bottom mirror))
    )
    (fp_text user "License: Apache-2.0" (at -0.95 -5.169 90) (layer "B.Fab") hide
        (effects (font (size 0.7 0.7) (thickness 0.15)) (justify left bottom mirror))
    )
    (fp_text user "${REFERENCE}" (at -0.95 -3.168 90) (layer "B.Fab") hide
        (effects (font (size 0.7 0.7) (thickness 0.15)) (justify left bottom mirror))
    )
    (fp_rect (start -0.93 0.47) (end 0.93 -0.47)
      (stroke (width 0.05) (type solid)) (fill none) (layer "B.CrtYd"))
    (fp_rect (start -0.5 0.25) (end 0.5 -0.25)
      (stroke (width 0.15) (type solid)) (fill none) (layer "B.Fab"))
    (pad "1" smd roundrect (at -0.485 0 270) (size 0.59 0.64) (layers "B.Cu" "B.Paste" "B.Mask") (roundrect_rratio 0.25)
      (net 77 "VCCA_DPHY") (pintype "passive"))
    (pad "2" smd roundrect (at 0.485 0 270) (size 0.59 0.64) (layers "B.Cu" "B.Paste" "B.Mask") (roundrect_rratio 0.25)
      (net 85 "Net-(U4-VCCA_DPHY1)") (pintype "passive"))
  )
	(footprint "sdi-mipi-bridge-footprints:R_0402_1005Metric" (layer "B.Cu")
    (at 145.315 119.295)
    (descr "Resistor SMD 0402")
    (tags "resistor SMD 0402")
    (property "Author" "Antmicro")
    (property "Current" "1A")
    (property "License" "Apache-2.0")
    (property "MPN" "ERJ2GE0R00X")
    (property "Manufacturer" "Panasonic")
    (property "Sheetfile" "sdi-mipi-bridge.kicad_sch")
    (property "Sheetname" "")
    (property "Tolerance" "")
    (property "Val" "0R")
    (property "ki_description" "0R resistor in 0402 package with unspecified tolerance")
    (attr smd)
    (fp_text reference "R91" (at 7.685 8.105) (layer "B.SilkS")
        (effects (font (size 0.7 0.7) (thickness 0.15)) (justify right bottom mirror))
    )
    (fp_text value "R_0R_0402" (at 0 -1.4) (layer "B.Fab") hide
        (effects (font (size 0.7 0.7) (thickness 0.15)) (justify right bottom mirror))
    )
    (fp_text user "${REFERENCE}" (at -0.95 -3.168) (layer "B.Fab") hide
        (effects (font (size 0.7 0.7) (thickness 0.15)) (justify right bottom mirror))
    )
    (fp_text user "License: Apache-2.0" (at -0.95 -5.169) (layer "B.Fab") hide
        (effects (font (size 0.7 0.7) (thickness 0.15)) (justify right bottom mirror))
    )
    (fp_text user "Author: Antmicro" (at -0.95 -4.169) (layer "B.Fab") hide
        (effects (font (size 0.7 0.7) (thickness 0.15)) (justify right bottom mirror))
    )
    (fp_rect (start -0.93 0.47) (end 0.93 -0.47)
      (stroke (width 0.05) (type solid)) (fill none) (layer "B.CrtYd"))
    (fp_rect (start -0.5 0.25) (end 0.5 -0.25)
      (stroke (width 0.15) (type solid)) (fill none) (layer "B.Fab"))
    (pad "1" smd roundrect (at -0.485 0) (size 0.59 0.64) (layers "B.Cu" "B.Paste" "B.Mask") (roundrect_rratio 0.25)
      (net 77 "VCCA_DPHY") (pintype "passive"))
    (pad "2" smd roundrect (at 0.485 0) (size 0.59 0.64) (layers "B.Cu" "B.Paste" "B.Mask") (roundrect_rratio 0.25)
      (net 104 "Net-(U4-VCCA_DPHY0)") (pintype "passive"))
  )
	(footprint "sdi-mipi-bridge-footprints:C_0402_1005Metric" (layer "B.Cu")
    (at 118 110.9 -90)
    (descr "Capacitor SMD 0402")
    (tags "capacitor SMD 0402")
    (property "Author" "Antmicro")
    (property "Dielectric" "X7R")
    (property "License" "Apache-2.0")
    (property "MPN" "GRM155R71H103KA88D")
    (property "Manufacturer" "Murata")
    (property "Sheetfile" "sdi-mipi-bridge.kicad_sch")
    (property "Sheetname" "")
    (property "Val" "10n")
    (property "Voltage" "50V")
    (property "ki_description" " ")
    (attr smd)
    (fp_text reference "C11" (at -4.3 -0.4 90) (layer "B.SilkS")
        (effects (font (size 0.7 0.7) (thickness 0.15)) (justify left bottom mirror))
    )
    (fp_text value "C_10n_0402" (at 0 -1.4 90) (layer "B.Fab") hide
        (effects (font (size 0.7 0.7) (thickness 0.15)) (justify left bottom mirror))
    )
    (fp_text user "License: Apache-2.0" (at -0.932 -5.17 90) (layer "B.Fab") hide
        (effects (font (size 0.7 0.7) (thickness 0.15)) (justify left bottom mirror))
    )
    (fp_text user "${REFERENCE}" (at -0.932 -3.168 90) (layer "B.Fab") hide
        (effects (font (size 0.7 0.7) (thickness 0.15)) (justify left bottom mirror))
    )
    (fp_text user "Author: Antmicro" (at -0.932 -4.17 90) (layer "B.Fab") hide
        (effects (font (size 0.7 0.7) (thickness 0.15)) (justify left bottom mirror))
    )
    (fp_rect (start -0.94 0.47) (end 0.94 -0.47)
      (stroke (width 0.05) (type solid)) (fill none) (layer "B.CrtYd"))
    (fp_rect (start -0.499 0.249) (end 0.499 -0.249)
      (stroke (width 0.15) (type solid)) (fill none) (layer "B.Fab"))
    (pad "1" smd roundrect (at -0.484 0 270) (size 0.59 0.64) (layers "B.Cu" "B.Paste" "B.Mask") (roundrect_rratio 0.25)
      (net 3 "GNDA") (pintype "passive"))
    (pad "2" smd roundrect (at 0.484 0 270) (size 0.59 0.64) (layers "B.Cu" "B.Paste" "B.Mask") (roundrect_rratio 0.25)
      (net 4 "VPP") (pintype "passive"))
  )
	(footprint "sdi-mipi-bridge-footprints:C_0402_1005Metric" (layer "B.Cu")
    (at 119 110.9 -90)
    (descr "Capacitor SMD 0402")
    (tags "capacitor SMD 0402")
    (property "Author" "Antmicro")
    (property "Dielectric" "X7R")
    (property "License" "Apache-2.0")
    (property "MPN" "GRM155R71H103KA88D")
    (property "Manufacturer" "Murata")
    (property "Sheetfile" "sdi-mipi-bridge.kicad_sch")
    (property "Sheetname" "")
    (property "Val" "10n")
    (property "Voltage" "50V")
    (property "ki_description" " ")
    (attr smd)
    (fp_text reference "C13" (at -4.3 -0.4 90) (layer "B.SilkS")
        (effects (font (size 0.7 0.7) (thickness 0.15)) (justify left bottom mirror))
    )
    (fp_text value "C_10n_0402" (at 0 -1.4 90) (layer "B.Fab") hide
        (effects (font (size 0.7 0.7) (thickness 0.15)) (justify left bottom mirror))
    )
    (fp_text user "${REFERENCE}" (at -0.932 -3.168 90) (layer "B.Fab") hide
        (effects (font (size 0.7 0.7) (thickness 0.15)) (justify left bottom mirror))
    )
    (fp_text user "License: Apache-2.0" (at -0.932 -5.17 90) (layer "B.Fab") hide
        (effects (font (size 0.7 0.7) (thickness 0.15)) (justify left bottom mirror))
    )
    (fp_text user "Author: Antmicro" (at -0.932 -4.17 90) (layer "B.Fab") hide
        (effects (font (size 0.7 0.7) (thickness 0.15)) (justify left bottom mirror))
    )
    (fp_rect (start -0.94 0.47) (end 0.94 -0.47)
      (stroke (width 0.05) (type solid)) (fill none) (layer "B.CrtYd"))
    (fp_rect (start -0.499 0.249) (end 0.499 -0.249)
      (stroke (width 0.15) (type solid)) (fill none) (layer "B.Fab"))
    (pad "1" smd roundrect (at -0.484 0 270) (size 0.59 0.64) (layers "B.Cu" "B.Paste" "B.Mask") (roundrect_rratio 0.25)
      (net 3 "GNDA") (pintype "passive"))
    (pad "2" smd roundrect (at 0.484 0 270) (size 0.59 0.64) (layers "B.Cu" "B.Paste" "B.Mask") (roundrect_rratio 0.25)
      (net 4 "VPP") (pintype "passive"))
  )
	(footprint "sdi-mipi-bridge-footprints:C_0402_1005Metric" (layer "B.Cu")
    (at 117 110.9 -90)
    (descr "Capacitor SMD 0402")
    (tags "capacitor SMD 0402")
    (property "Author" "Antmicro")
    (property "Dielectric" "X7R")
    (property "License" "Apache-2.0")
    (property "MPN" "GRM155R71H103KA88D")
    (property "Manufacturer" "Murata")
    (property "Sheetfile" "sdi-mipi-bridge.kicad_sch")
    (property "Sheetname" "")
    (property "Val" "10n")
    (property "Voltage" "50V")
    (property "ki_description" " ")
    (attr smd)
    (fp_text reference "C16" (at -4.3 -0.4 90) (layer "B.SilkS")
        (effects (font (size 0.7 0.7) (thickness 0.15)) (justify left bottom mirror))
    )
    (fp_text value "C_10n_0402" (at 0 -1.4 90) (layer "B.Fab") hide
        (effects (font (size 0.7 0.7) (thickness 0.15)) (justify left bottom mirror))
    )
    (fp_text user "${REFERENCE}" (at -0.932 -3.168 90) (layer "B.Fab") hide
        (effects (font (size 0.7 0.7) (thickness 0.15)) (justify left bottom mirror))
    )
    (fp_text user "Author: Antmicro" (at -0.932 -4.17 90) (layer "B.Fab") hide
        (effects (font (size 0.7 0.7) (thickness 0.15)) (justify left bottom mirror))
    )
    (fp_text user "License: Apache-2.0" (at -0.932 -5.17 90) (layer "B.Fab") hide
        (effects (font (size 0.7 0.7) (thickness 0.15)) (justify left bottom mirror))
    )
    (fp_rect (start -0.94 0.47) (end 0.94 -0.47)
      (stroke (width 0.05) (type solid)) (fill none) (layer "B.CrtYd"))
    (fp_rect (start -0.499 0.249) (end 0.499 -0.249)
      (stroke (width 0.15) (type solid)) (fill none) (layer "B.Fab"))
    (pad "1" smd roundrect (at -0.484 0 270) (size 0.59 0.64) (layers "B.Cu" "B.Paste" "B.Mask") (roundrect_rratio 0.25)
      (net 3 "GNDA") (pintype "passive"))
    (pad "2" smd roundrect (at 0.484 0 270) (size 0.59 0.64) (layers "B.Cu" "B.Paste" "B.Mask") (roundrect_rratio 0.25)
      (net 4 "VPP") (pintype "passive"))
  )
	(footprint "sdi-mipi-bridge-footprints:C_0402_1005Metric" (layer "B.Cu")
    (at 120 115.4)
    (descr "Capacitor SMD 0402")
    (tags "capacitor SMD 0402")
    (property "Author" "Antmicro")
    (property "Dielectric" "X7R")
    (property "License" "Apache-2.0")
    (property "MPN" "GRM155R71H103KA88D")
    (property "Manufacturer" "Murata")
    (property "Sheetfile" "sdi-mipi-bridge.kicad_sch")
    (property "Sheetname" "")
    (property "Val" "10n")
    (property "Voltage" "50V")
    (property "ki_description" " ")
    (attr smd)
    (fp_text reference "C6" (at -2.2 0.4) (layer "B.SilkS")
        (effects (font (size 0.7 0.7) (thickness 0.15)) (justify right bottom mirror))
    )
    (fp_text value "C_10n_0402" (at 0 -1.4) (layer "B.Fab") hide
        (effects (font (size 0.7 0.7) (thickness 0.15)) (justify right bottom mirror))
    )
    (fp_text user "${REFERENCE}" (at -0.932 -3.168) (layer "B.Fab") hide
        (effects (font (size 0.7 0.7) (thickness 0.15)) (justify right bottom mirror))
    )
    (fp_text user "License: Apache-2.0" (at -0.932 -5.17) (layer "B.Fab") hide
        (effects (font (size 0.7 0.7) (thickness 0.15)) (justify right bottom mirror))
    )
    (fp_text user "Author: Antmicro" (at -0.932 -4.17) (layer "B.Fab") hide
        (effects (font (size 0.7 0.7) (thickness 0.15)) (justify right bottom mirror))
    )
    (fp_rect (start -0.94 0.47) (end 0.94 -0.47)
      (stroke (width 0.05) (type solid)) (fill none) (layer "B.CrtYd"))
    (fp_rect (start -0.499 0.249) (end 0.499 -0.249)
      (stroke (width 0.15) (type solid)) (fill none) (layer "B.Fab"))
    (pad "1" smd roundrect (at -0.484 0) (size 0.59 0.64) (layers "B.Cu" "B.Paste" "B.Mask") (roundrect_rratio 0.25)
      (net 1 "GNDREF") (pintype "passive"))
    (pad "2" smd roundrect (at 0.484 0) (size 0.59 0.64) (layers "B.Cu" "B.Paste" "B.Mask") (roundrect_rratio 0.25)
      (net 2 "+1V2") (pintype "passive"))
  )
	(footprint "sdi-mipi-bridge-footprints:C_0402_1005Metric" (layer "B.Cu")
    (at 122 115.4)
    (descr "Capacitor SMD 0402")
    (tags "capacitor SMD 0402")
    (property "Author" "Antmicro")
    (property "Dielectric" "X7R")
    (property "License" "Apache-2.0")
    (property "MPN" "GRM155R71H103KA88D")
    (property "Manufacturer" "Murata")
    (property "Sheetfile" "sdi-mipi-bridge.kicad_sch")
    (property "Sheetname" "")
    (property "Val" "10n")
    (property "Voltage" "50V")
    (property "ki_description" " ")
    (attr smd)
    (fp_text reference "C8" (at 0.8 0.4) (layer "B.SilkS")
        (effects (font (size 0.7 0.7) (thickness 0.15)) (justify right bottom mirror))
    )
    (fp_text value "C_10n_0402" (at 0 -1.4) (layer "B.Fab") hide
        (effects (font (size 0.7 0.7) (thickness 0.15)) (justify right bottom mirror))
    )
    (fp_text user "${REFERENCE}" (at -0.932 -3.168) (layer "B.Fab") hide
        (effects (font (size 0.7 0.7) (thickness 0.15)) (justify right bottom mirror))
    )
    (fp_text user "Author: Antmicro" (at -0.932 -4.17) (layer "B.Fab") hide
        (effects (font (size 0.7 0.7) (thickness 0.15)) (justify right bottom mirror))
    )
    (fp_text user "License: Apache-2.0" (at -0.932 -5.17) (layer "B.Fab") hide
        (effects (font (size 0.7 0.7) (thickness 0.15)) (justify right bottom mirror))
    )
    (fp_rect (start -0.94 0.47) (end 0.94 -0.47)
      (stroke (width 0.05) (type solid)) (fill none) (layer "B.CrtYd"))
    (fp_rect (start -0.499 0.249) (end 0.499 -0.249)
      (stroke (width 0.15) (type solid)) (fill none) (layer "B.Fab"))
    (pad "1" smd roundrect (at -0.484 0) (size 0.59 0.64) (layers "B.Cu" "B.Paste" "B.Mask") (roundrect_rratio 0.25)
      (net 1 "GNDREF") (pintype "passive"))
    (pad "2" smd roundrect (at 0.484 0) (size 0.59 0.64) (layers "B.Cu" "B.Paste" "B.Mask") (roundrect_rratio 0.25)
      (net 2 "+1V2") (pintype "passive"))
  )
	(footprint "sdi-mipi-bridge-footprints:C_0402_1005Metric" (layer "B.Cu")
    (at 126.5 110.9 -90)
    (descr "Capacitor SMD 0402")
    (tags "capacitor SMD 0402")
    (property "Author" "Antmicro")
    (property "Dielectric" "X7R")
    (property "License" "Apache-2.0")
    (property "MPN" "GRM155R71H103KA88D")
    (property "Manufacturer" "Murata")
    (property "Sheetfile" "sdi-mipi-bridge.kicad_sch")
    (property "Sheetname" "")
    (property "Val" "10n")
    (property "Voltage" "50V")
    (property "ki_description" " ")
    (attr smd)
    (fp_text reference "C7" (at 0.9 -0.3 90) (layer "B.SilkS")
        (effects (font (size 0.7 0.7) (thickness 0.15)) (justify left bottom mirror))
    )
    (fp_text value "C_10n_0402" (at 0 -1.4 90) (layer "B.Fab") hide
        (effects (font (size 0.7 0.7) (thickness 0.15)) (justify left bottom mirror))
    )
    (fp_text user "Author: Antmicro" (at -0.932 -4.17 90) (layer "B.Fab") hide
        (effects (font (size 0.7 0.7) (thickness 0.15)) (justify left bottom mirror))
    )
    (fp_text user "${REFERENCE}" (at -0.932 -3.168 90) (layer "B.Fab") hide
        (effects (font (size 0.7 0.7) (thickness 0.15)) (justify left bottom mirror))
    )
    (fp_text user "License: Apache-2.0" (at -0.932 -5.17 90) (layer "B.Fab") hide
        (effects (font (size 0.7 0.7) (thickness 0.15)) (justify left bottom mirror))
    )
    (fp_rect (start -0.94 0.47) (end 0.94 -0.47)
      (stroke (width 0.05) (type solid)) (fill none) (layer "B.CrtYd"))
    (fp_rect (start -0.499 0.249) (end 0.499 -0.249)
      (stroke (width 0.15) (type solid)) (fill none) (layer "B.Fab"))
    (pad "1" smd roundrect (at -0.484 0 270) (size 0.59 0.64) (layers "B.Cu" "B.Paste" "B.Mask") (roundrect_rratio 0.25)
      (net 1 "GNDREF") (pintype "passive"))
    (pad "2" smd roundrect (at 0.484 0 270) (size 0.59 0.64) (layers "B.Cu" "B.Paste" "B.Mask") (roundrect_rratio 0.25)
      (net 76 "IO_VDD") (pintype "passive"))
  )
	(footprint "sdi-mipi-bridge-footprints:C_0402_1005Metric" (layer "B.Cu")
    (at 134.05 134.08)
    (descr "Capacitor SMD 0402")
    (tags "capacitor SMD 0402")
    (property "Author" "Antmicro")
    (property "Dielectric" "X7R")
    (property "License" "Apache-2.0")
    (property "MPN" "GRM155R71H103KA88D")
    (property "Manufacturer" "Murata")
    (property "Sheetfile" "sdi-mipi-bridge.kicad_sch")
    (property "Sheetname" "")
    (property "Val" "10n")
    (property "Voltage" "50V")
    (property "ki_description" " ")
    (attr smd)
    (fp_text reference "C20" (at 2.15 0.32) (layer "B.SilkS")
        (effects (font (size 0.7 0.7) (thickness 0.15)) (justify right bottom mirror))
    )
    (fp_text value "C_10n_0402" (at 100 -1.423) (layer "B.Fab") hide
        (effects (font (size 0.7 0.7) (thickness 0.15)) (justify right bottom mirror))
    )
    (fp_text user "Author: Antmicro" (at -0.932 -4.17) (layer "B.Fab") hide
        (effects (font (size 0.7 0.7) (thickness 0.15)) (justify right bottom mirror))
    )
    (fp_text user "${REFERENCE}" (at -0.932 -3.168) (layer "B.Fab") hide
        (effects (font (size 0.7 0.7) (thickness 0.15)) (justify right bottom mirror))
    )
    (fp_text user "License: Apache-2.0" (at -0.932 -5.17) (layer "B.Fab") hide
        (effects (font (size 0.7 0.7) (thickness 0.15)) (justify right bottom mirror))
    )
    (fp_rect (start -0.94 0.47) (end 0.94 -0.47)
      (stroke (width 0.05) (type solid)) (fill none) (layer "B.CrtYd"))
    (fp_rect (start -0.499 0.249) (end 0.499 -0.249)
      (stroke (width 0.15) (type solid)) (fill none) (layer "B.Fab"))
    (pad "1" smd roundrect (at -0.484 0) (size 0.59 0.64) (layers "B.Cu" "B.Paste" "B.Mask") (roundrect_rratio 0.25)
      (net 1 "GNDREF") (pintype "passive"))
    (pad "2" smd roundrect (at 0.484 0) (size 0.59 0.64) (layers "B.Cu" "B.Paste" "B.Mask") (roundrect_rratio 0.25)
      (net 2 "+1V2") (pintype "passive"))
  )
)
